FILE_TYPE = MACRO_DRAWING;
SET COLOR_WIRE YELLOW;
SET COLOR_PROP ORANGE;
SET COLOR_DOT WHITE;
SET COLOR_ARC YELLOW;
SET COLOR_BODY GREEN;
SET COLOR_NOTE PURPLE;
SET PROP_DISPLAY VALUE;
SET PAGE_NUMBER P117;
FORCEADD Q_RES..1
(-700 3350);
FORCEPROP 1 LAST PART_NUMBER CS00002JB13
J 0
(-750 3400);
DISPLAY 0.404255 (-750 3400);
DISPLAY INVISIBLE (-750 3400);
FORCEPROP 1 LAST MATERIAL CHIP
J 0
(-750 3425);
DISPLAY 0.404255 (-750 3425);
FORCEPROP 1 LAST WATTAGE 1/16W
J 2
(-525 3425);
DISPLAY 0.404255 (-525 3425);
FORCEPROP 1 LAST VALUE 0
J 2
(-550 3350);
DISPLAY 0.510638 (-550 3350);
FORCEPROP 1 LAST TOLERANCE 5%
J 0
(-525 3350);
DISPLAY 0.510638 (-525 3350);
FORCEPROP 1 LAST PACK_TYPE 0402LF
J 0
(-750 3450);
DISPLAY 0.404255 (-750 3450);
FORCEPROP 1 LAST $LOCATION R3023
J 0
(-925 3350);
DISPLAY 0.638298 (-925 3350);
FORCEPROP 1 LASTPIN (-800 3350) $PN 1
J 0
(-788 3362);
DISPLAY 0.787234 (-788 3362);
FORCEPROP 1 LASTPIN (-600 3350) $PN 2
J 0
(-638 3362);
DISPLAY 0.787234 (-638 3362);
FORCEPROP 2 LAST CDS_LIB pure_quanta
J 0
(-700 3350);
PAINT MONO (-700 3350);
DISPLAY INVISIBLE (-700 3350);
FORCEPROP 1 LAST PATH I10
J 0
(-750 3500);
DISPLAY 0.978723 (-750 3500);
PAINT WHITE (-750 3500);
DISPLAY INVISIBLE (-750 3500);
FORCEPROP 2 LAST CDS_LOCATION R3023
J 0
(-750 3550);
DISPLAY 1.021277 (-750 3550);
DISPLAY INVISIBLE (-750 3550);
FORCEPROP 2 LAST $SEC 1
J 0
(-750 3550);
DISPLAY 0.680851 (-750 3550);
PAINT MONO (-750 3550);
DISPLAY INVISIBLE (-750 3550);
FORCEPROP 2 LAST CDS_SEC 1
J 0
(-750 3550);
DISPLAY 1.021277 (-750 3550);
DISPLAY INVISIBLE (-750 3550);
FORCEADD OFFPAGE..3
R 2
(-3400 3350);
FORCEPROP 2 LAST $XR0 14 
J 0
(-3679 3350);
DISPLAY 0.638298 (-3679 3350);
PAINT MONO (-3679 3350);
FORCEPROP 2 LAST CDS_LIB standard
J 0
(-3400 3350);
PAINT MONO (-3400 3350);
DISPLAY INVISIBLE (-3400 3350);
FORCEPROP 1 LAST OFFPAGE TRUE
J 2
(-3725 3225);
DISPLAY 0.872340 (-3725 3225);
DISPLAY INVISIBLE (-3725 3225);
FORCEPROP 1 LAST COMMENT_BODY TRUE
J 2
(-3350 3250);
DISPLAY 0.872340 (-3350 3250);
PAINT GREEN (-3350 3250);
DISPLAY INVISIBLE (-3350 3250);
FORCEPROP 2 LAST PATH I11
J 0
(-3725 3400);
DISPLAY 1.021277 (-3725 3400);
DISPLAY INVISIBLE (-3725 3400);
FORCEADD OFFPAGE..3
(500 3350);
FORCEPROP 2 LAST $XR0 45 
J 0
(714 3350);
DISPLAY 0.638298 (714 3350);
PAINT MONO (714 3350);
FORCEPROP 2 LAST CDS_LIB standard
J 0
(500 3350);
PAINT MONO (500 3350);
DISPLAY INVISIBLE (500 3350);
FORCEPROP 1 LAST OFFPAGE TRUE
J 0
(825 3225);
DISPLAY 0.872340 (825 3225);
PAINT GREEN (825 3225);
DISPLAY INVISIBLE (825 3225);
FORCEPROP 1 LAST COMMENT_BODY TRUE
J 0
(450 3250);
DISPLAY 0.872340 (450 3250);
PAINT GREEN (450 3250);
DISPLAY INVISIBLE (450 3250);
FORCEPROP 2 LAST PATH I12
J 0
(725 3400);
DISPLAY 1.021277 (725 3400);
DISPLAY INVISIBLE (725 3400);
FORCEADD Q_RES..2
(-1875 3650);
FORCEPROP 1 LAST PART_NUMBER CS13012FB02
J 0
(-1835 3525);
DISPLAY 0.510638 (-1835 3525);
DISPLAY INVISIBLE (-1835 3525);
FORCEPROP 1 LAST MATERIAL CHIP
J 0
(-1835 3575);
DISPLAY 0.510638 (-1835 3575);
FORCEPROP 1 LAST PACK_TYPE 0402LF
J 0
(-1835 3475);
DISPLAY 0.510638 (-1835 3475);
FORCEPROP 1 LAST TOLERANCE 1%
J 0
(-1830 3675);
DISPLAY 0.510638 (-1830 3675);
FORCEPROP 1 LAST WATTAGE 1/16W
J 0
(-1835 3625);
DISPLAY 0.510638 (-1835 3625);
FORCEPROP 1 LAST VALUE 301
J 0
(-1830 3725);
DISPLAY 0.510638 (-1830 3725);
FORCEPROP 1 LAST $LOCATION R1242
J 0
(-1830 3775);
DISPLAY 0.978723 (-1830 3775);
FORCEPROP 1 LASTPIN (-1875 3750) $PN 1
J 0
(-1870 3712);
DISPLAY 0.787234 (-1870 3712);
FORCEPROP 1 LASTPIN (-1875 3550) $PN 2
J 0
(-1870 3560);
DISPLAY 0.787234 (-1870 3560);
FORCEPROP 2 LAST CDS_LIB pure_quanta
J 0
(-1875 3650);
PAINT MONO (-1875 3650);
DISPLAY INVISIBLE (-1875 3650);
FORCEPROP 1 LAST PATH I13
J 0
(-1825 3825);
DISPLAY 0.978723 (-1825 3825);
PAINT WHITE (-1825 3825);
DISPLAY INVISIBLE (-1825 3825);
FORCEPROP 2 LAST CDS_LOCATION R1242
J 0
(-1825 3875);
DISPLAY 1.021277 (-1825 3875);
DISPLAY INVISIBLE (-1825 3875);
FORCEPROP 2 LAST $SEC 1
J 0
(-1825 3875);
DISPLAY 0.680851 (-1825 3875);
PAINT MONO (-1825 3875);
DISPLAY INVISIBLE (-1825 3875);
FORCEPROP 2 LAST CDS_SEC 1
J 0
(-1825 3875);
DISPLAY 1.021277 (-1825 3875);
DISPLAY INVISIBLE (-1825 3875);
FORCEADD UNIVERSAL_POWER..1
(-1875 3925);
FORCEPROP 3 LASTPIN (-1875 3875) SIG_NAME PVNN_TERM_CPU0\g
J 0
(-1865 3885);
DISPLAY 0.659574 (-1865 3885);
PAINT MONO (-1865 3885);
DISPLAY INVISIBLE (-1865 3885);
FORCEPROP 1 LAST HDL_POWER PVNN_TERM_CPU0
J 1
(-1875 3975);
DISPLAY 0.872340 (-1875 3975);
PAINT GREEN (-1875 3975);
FORCEPROP 2 LAST CDS_LIB logical_power
J 0
(-1875 3925);
PAINT MONO (-1875 3925);
DISPLAY INVISIBLE (-1875 3925);
FORCEPROP 1 LAST PATH I14
J 0
(-1825 3950);
DISPLAY 0.872340 (-1825 3950);
PAINT AQUA (-1825 3950);
DISPLAY INVISIBLE (-1825 3950);
FORCEADD UNIVERSAL_POWER..1
(-1075 3925);
FORCEPROP 3 LASTPIN (-1075 3875) SIG_NAME PVNN_TERM_CPU1\g
J 0
(-1065 3885);
DISPLAY 0.659574 (-1065 3885);
PAINT MONO (-1065 3885);
DISPLAY INVISIBLE (-1065 3885);
FORCEPROP 1 LAST HDL_POWER PVNN_TERM_CPU1
J 1
(-1075 3975);
DISPLAY 0.872340 (-1075 3975);
PAINT GREEN (-1075 3975);
FORCEPROP 2 LAST CDS_LIB logical_power
J 0
(-1075 3925);
PAINT MONO (-1075 3925);
DISPLAY INVISIBLE (-1075 3925);
FORCEPROP 1 LAST PATH I15
J 0
(-1025 3950);
DISPLAY 0.872340 (-1025 3950);
PAINT AQUA (-1025 3950);
DISPLAY INVISIBLE (-1025 3950);
FORCEADD Q_RES..2
(-1075 3650);
FORCEPROP 1 LAST PART_NUMBER CS13012FB02
J 0
(-1035 3525);
DISPLAY 0.510638 (-1035 3525);
DISPLAY INVISIBLE (-1035 3525);
FORCEPROP 1 LAST VALUE 301
J 0
(-1030 3725);
DISPLAY 0.510638 (-1030 3725);
FORCEPROP 1 LAST MATERIAL CHIP
J 0
(-1035 3575);
DISPLAY 0.510638 (-1035 3575);
FORCEPROP 1 LAST WATTAGE 1/16W
J 0
(-1035 3625);
DISPLAY 0.510638 (-1035 3625);
FORCEPROP 1 LAST PACK_TYPE 0402LF
J 0
(-1035 3475);
DISPLAY 0.510638 (-1035 3475);
FORCEPROP 1 LAST TOLERANCE 1%
J 0
(-1030 3675);
DISPLAY 0.510638 (-1030 3675);
FORCEPROP 1 LAST $LOCATION R1244
J 0
(-1030 3775);
DISPLAY 0.978723 (-1030 3775);
FORCEPROP 1 LASTPIN (-1075 3750) $PN 1
J 0
(-1070 3712);
DISPLAY 0.787234 (-1070 3712);
FORCEPROP 1 LASTPIN (-1075 3550) $PN 2
J 0
(-1070 3560);
DISPLAY 0.787234 (-1070 3560);
FORCEPROP 2 LAST CDS_LIB pure_quanta
J 0
(-1075 3650);
PAINT MONO (-1075 3650);
DISPLAY INVISIBLE (-1075 3650);
FORCEPROP 1 LAST PATH I16
J 0
(-1025 3825);
DISPLAY 0.978723 (-1025 3825);
PAINT WHITE (-1025 3825);
DISPLAY INVISIBLE (-1025 3825);
FORCEPROP 2 LAST CDS_LOCATION R1244
J 0
(-1025 3875);
DISPLAY 1.021277 (-1025 3875);
DISPLAY INVISIBLE (-1025 3875);
FORCEPROP 2 LAST $SEC 1
J 0
(-1025 3875);
DISPLAY 0.680851 (-1025 3875);
PAINT MONO (-1025 3875);
DISPLAY INVISIBLE (-1025 3875);
FORCEPROP 2 LAST CDS_SEC 1
J 0
(-1025 3875);
DISPLAY 1.021277 (-1025 3875);
DISPLAY INVISIBLE (-1025 3875);
FORCEADD Q_RES..2
(-3100 5100);
FORCEPROP 1 LAST PART_NUMBER CS12492FB02
J 0
(-3060 4975);
DISPLAY 0.638298 (-3060 4975);
DISPLAY INVISIBLE (-3060 4975);
FORCEPROP 1 LAST MATERIAL CHIP
J 0
(-3060 5025);
DISPLAY 0.638298 (-3060 5025);
FORCEPROP 1 LAST PACK_TYPE 0402LF
J 0
(-3060 4975);
DISPLAY 0.638298 (-3060 4975);
FORCEPROP 1 LAST VALUE 249
J 0
(-3055 5175);
DISPLAY 0.638298 (-3055 5175);
FORCEPROP 1 LAST WATTAGE 1/16W
J 0
(-3060 5075);
DISPLAY 0.638298 (-3060 5075);
FORCEPROP 1 LAST TOLERANCE 1%
J 0
(-3055 5125);
DISPLAY 0.638298 (-3055 5125);
FORCEPROP 1 LAST $LOCATION R1241
J 0
(-3055 5225);
DISPLAY 0.978723 (-3055 5225);
FORCEPROP 1 LASTPIN (-3100 5200) $PN 1
J 0
(-3095 5162);
DISPLAY 0.787234 (-3095 5162);
FORCEPROP 1 LASTPIN (-3100 5000) $PN 2
J 0
(-3095 5010);
DISPLAY 0.787234 (-3095 5010);
FORCEPROP 2 LAST CDS_LIB pure_quanta
J 0
(-3100 5100);
PAINT MONO (-3100 5100);
DISPLAY INVISIBLE (-3100 5100);
FORCEPROP 1 LAST PATH I17
J 0
(-3050 5275);
DISPLAY 0.978723 (-3050 5275);
PAINT WHITE (-3050 5275);
DISPLAY INVISIBLE (-3050 5275);
FORCEPROP 2 LAST CDS_LOCATION R1241
J 0
(-3050 5325);
DISPLAY 1.021277 (-3050 5325);
DISPLAY INVISIBLE (-3050 5325);
FORCEPROP 2 LAST $SEC 1
J 0
(-3050 5325);
DISPLAY 0.680851 (-3050 5325);
PAINT MONO (-3050 5325);
DISPLAY INVISIBLE (-3050 5325);
FORCEPROP 2 LAST CDS_SEC 1
J 0
(-3050 5325);
DISPLAY 1.021277 (-3050 5325);
DISPLAY INVISIBLE (-3050 5325);
FORCEADD UNIVERSAL_GND..1
(-3100 4850);
FORCEPROP 3 LASTPIN (-3100 4900) SIG_NAME GND\g
J 0
(-3090 4910);
DISPLAY 0.659574 (-3090 4910);
PAINT MONO (-3090 4910);
DISPLAY INVISIBLE (-3090 4910);
FORCEPROP 2 LAST CDS_LIB logical_power
J 0
(-3100 4850);
PAINT MONO (-3100 4850);
DISPLAY INVISIBLE (-3100 4850);
FORCEPROP 1 LAST HDL_POWER GND
J 1
(-3075 4775);
DISPLAY 0.872340 (-3075 4775);
PAINT GREEN (-3075 4775);
DISPLAY INVISIBLE (-3075 4775);
FORCEPROP 1 LAST PATH I18
J 0
(-3025 4850);
DISPLAY 0.872340 (-3025 4850);
PAINT AQUA (-3025 4850);
DISPLAY INVISIBLE (-3025 4850);
FORCEADD Q_RES..2
(-2825 5100);
FORCEPROP 1 LAST PART_NUMBER CS12492FB02
J 0
(-2785 4925);
DISPLAY 0.638298 (-2785 4925);
DISPLAY INVISIBLE (-2785 4925);
FORCEPROP 1 LAST WATTAGE 1/16W
J 0
(-2785 5075);
DISPLAY 0.638298 (-2785 5075);
FORCEPROP 1 LAST TOLERANCE 1%
J 0
(-2780 5125);
DISPLAY 0.638298 (-2780 5125);
FORCEPROP 1 LAST MATERIAL CHIP
J 0
(-2785 5025);
DISPLAY 0.638298 (-2785 5025);
FORCEPROP 1 LAST VALUE 249
J 0
(-2780 5175);
DISPLAY 0.638298 (-2780 5175);
FORCEPROP 1 LAST PACK_TYPE 0402LF
J 0
(-2785 4975);
DISPLAY 0.638298 (-2785 4975);
FORCEPROP 1 LAST $LOCATION R1243
J 0
(-2780 5225);
DISPLAY 0.978723 (-2780 5225);
FORCEPROP 1 LASTPIN (-2825 5200) $PN 1
J 0
(-2820 5162);
DISPLAY 0.787234 (-2820 5162);
FORCEPROP 1 LASTPIN (-2825 5000) $PN 2
J 0
(-2820 5010);
DISPLAY 0.787234 (-2820 5010);
FORCEPROP 2 LAST CDS_LIB pure_quanta
J 0
(-2825 5100);
PAINT MONO (-2825 5100);
DISPLAY INVISIBLE (-2825 5100);
FORCEPROP 1 LAST PATH I19
J 0
(-2775 5275);
DISPLAY 0.978723 (-2775 5275);
PAINT WHITE (-2775 5275);
DISPLAY INVISIBLE (-2775 5275);
FORCEPROP 2 LAST CDS_LOCATION R1243
J 0
(-2775 5325);
DISPLAY 1.021277 (-2775 5325);
DISPLAY INVISIBLE (-2775 5325);
FORCEPROP 2 LAST $SEC 1
J 0
(-2775 5325);
DISPLAY 0.680851 (-2775 5325);
PAINT MONO (-2775 5325);
DISPLAY INVISIBLE (-2775 5325);
FORCEPROP 2 LAST CDS_SEC 1
J 0
(-2775 5325);
DISPLAY 1.021277 (-2775 5325);
DISPLAY INVISIBLE (-2775 5325);
FORCEADD UNIVERSAL_GND..1
(-2825 4850);
FORCEPROP 3 LASTPIN (-2825 4900) SIG_NAME GND\g
J 0
(-2815 4910);
DISPLAY 0.659574 (-2815 4910);
PAINT MONO (-2815 4910);
DISPLAY INVISIBLE (-2815 4910);
FORCEPROP 2 LAST CDS_LIB logical_power
J 0
(-2825 4850);
PAINT MONO (-2825 4850);
DISPLAY INVISIBLE (-2825 4850);
FORCEPROP 1 LAST HDL_POWER GND
J 1
(-2800 4775);
DISPLAY 0.872340 (-2800 4775);
PAINT GREEN (-2800 4775);
DISPLAY INVISIBLE (-2800 4775);
FORCEPROP 1 LAST PATH I20
J 0
(-2750 4850);
DISPLAY 0.872340 (-2750 4850);
PAINT AQUA (-2750 4850);
DISPLAY INVISIBLE (-2750 4850);
FORCEADD OFFPAGE..2
(-1350 5425);
FORCEPROP 2 LAST $XR0 16 
J 0
(-1161 5425);
DISPLAY 0.638298 (-1161 5425);
PAINT MONO (-1161 5425);
FORCEPROP 2 LAST CDS_LIB standard
J 0
(-1350 5425);
PAINT MONO (-1350 5425);
DISPLAY INVISIBLE (-1350 5425);
FORCEPROP 1 LAST OFFPAGE TRUE
J 0
(-1025 5300);
DISPLAY 0.872340 (-1025 5300);
PAINT GREEN (-1025 5300);
DISPLAY INVISIBLE (-1025 5300);
FORCEPROP 1 LAST COMMENT_BODY TRUE
J 0
(-1395 5330);
DISPLAY 0.872340 (-1395 5330);
PAINT GREEN (-1395 5330);
DISPLAY INVISIBLE (-1395 5330);
FORCEPROP 2 LAST PATH I6
J 0
(-1000 5475);
DISPLAY 1.021277 (-1000 5475);
DISPLAY INVISIBLE (-1000 5475);
FORCEADD OFFPAGE..2
(-1350 5325);
FORCEPROP 2 LAST $XR0 47 
J 0
(-1161 5325);
DISPLAY 0.638298 (-1161 5325);
PAINT MONO (-1161 5325);
FORCEPROP 2 LAST CDS_LIB standard
J 0
(-1350 5325);
PAINT MONO (-1350 5325);
DISPLAY INVISIBLE (-1350 5325);
FORCEPROP 1 LAST OFFPAGE TRUE
J 0
(-1025 5200);
DISPLAY 0.872340 (-1025 5200);
PAINT GREEN (-1025 5200);
DISPLAY INVISIBLE (-1025 5200);
FORCEPROP 1 LAST COMMENT_BODY TRUE
J 0
(-1395 5230);
DISPLAY 0.872340 (-1395 5230);
PAINT GREEN (-1395 5230);
DISPLAY INVISIBLE (-1395 5230);
FORCEPROP 2 LAST PATH I7
J 0
(-1000 5375);
DISPLAY 1.021277 (-1000 5375);
DISPLAY INVISIBLE (-1000 5375);
FORCEADD Q_RES..1
(-2175 3350);
FORCEPROP 1 LAST PART_NUMBER CS00002JB13
J 0
(-2225 3400);
DISPLAY 0.404255 (-2225 3400);
DISPLAY INVISIBLE (-2225 3400);
FORCEPROP 1 LAST PACK_TYPE 0402LF
J 0
(-2225 3450);
DISPLAY 0.404255 (-2225 3450);
FORCEPROP 1 LAST TOLERANCE 5%
J 0
(-2000 3350);
DISPLAY 0.510638 (-2000 3350);
FORCEPROP 1 LAST VALUE 0
J 2
(-2025 3350);
DISPLAY 0.510638 (-2025 3350);
FORCEPROP 1 LAST WATTAGE 1/16W
J 2
(-2000 3425);
DISPLAY 0.404255 (-2000 3425);
FORCEPROP 1 LAST MATERIAL CHIP
J 0
(-2225 3425);
DISPLAY 0.404255 (-2225 3425);
FORCEPROP 1 LAST $LOCATION R1240
J 0
(-2400 3350);
DISPLAY 0.638298 (-2400 3350);
FORCEPROP 1 LASTPIN (-2275 3350) $PN 1
J 0
(-2263 3362);
DISPLAY 0.787234 (-2263 3362);
FORCEPROP 1 LASTPIN (-2075 3350) $PN 2
J 0
(-2113 3362);
DISPLAY 0.787234 (-2113 3362);
FORCEPROP 2 LAST CDS_LIB pure_quanta
J 0
(-2175 3350);
PAINT MONO (-2175 3350);
DISPLAY INVISIBLE (-2175 3350);
FORCEPROP 1 LAST PATH I9
J 0
(-2225 3500);
DISPLAY 0.978723 (-2225 3500);
PAINT WHITE (-2225 3500);
DISPLAY INVISIBLE (-2225 3500);
FORCEPROP 2 LAST CDS_LOCATION R1240
J 0
(-2225 3550);
DISPLAY 1.021277 (-2225 3550);
DISPLAY INVISIBLE (-2225 3550);
FORCEPROP 2 LAST $SEC 1
J 0
(-2225 3550);
DISPLAY 0.680851 (-2225 3550);
PAINT MONO (-2225 3550);
DISPLAY INVISIBLE (-2225 3550);
FORCEPROP 2 LAST CDS_SEC 1
J 0
(-2225 3550);
DISPLAY 1.021277 (-2225 3550);
DISPLAY INVISIBLE (-2225 3550);
FORCEADD QUANTA_TITLE_BLOCK_C..1
(4875 -325);
FORCEPROP 0 LAST CDS_CON_LAST_MODIFIED Fri Aug 25 14:01:37 2023
J 0
(2990 -310);
PAINT MONO (2990 -310);
DISPLAY INVISIBLE (2990 -310);
FORCEPROP 2 LAST CUSTOM_TXT_CDS <XR_PAGE_TITLE>
J 0
(-3015 4925);
DISPLAY 0.638298 (-3015 4925);
PAINT PINK (-3015 4925);
DISPLAY INVISIBLE (-3015 4925);
FORCEPROP 2 LAST CUSTOM_TXT_CDS CR-112 : @ES_MB_LIB.ES_MB(SCH_1):PAGE112
J 0
(-3015 4925);
DISPLAY 0.638298 (-3015 4925);
PAINT PINK (-3015 4925);
DISPLAY INVISIBLE (-3015 4925);
FORCEPROP 2 LAST CUSTOM_TXT_CDS <CON_LAST_MODIFIED>
J 0
(2990 -310);
DISPLAY 0.978723 (2990 -310);
FORCEPROP 2 LAST CUSTOM_TXT_CDS <NAME_1>
J 0
(1775 -150);
FORCEPROP 2 LAST CUSTOM_TXT_CDS <CON_PAGE_NUM> OF <CON_TOTAL_PAGES>
J 0
(4425 -325);
DISPLAY 0.978723 (4425 -325);
FORCEPROP 2 LAST CUSTOM_TXT_CDS <Q_REV>
J 0
(4691 -222);
DISPLAY 1.212766 (4691 -222);
FORCEPROP 2 LAST CUSTOM_TXT_CDS <Q_NUMBER>
J 0
(3472 -222);
DISPLAY 1.212766 (3472 -222);
FORCEPROP 2 LAST CUSTOM_TXT_CDS <Q_PROJ>
J 0
(2550 -225);
DISPLAY 1.212766 (2550 -225);
FORCEPROP 2 LAST CUSTOM_TXT_CDS <NAME_2>
J 0
(1750 -275);
FORCEPROP 1 LAST Q_TITLE SPR CPU0 & 1 - SVID/MISC/UART
J 0
(-4391 -324);
DISPLAY 2.446809 (-4391 -324);
PAINT GREEN (-4391 -324);
FORCEPROP 1 LAST Q_DEPT 
J 1
(1112 -276);
DISPLAY 1.957447 (1112 -276);
PAINT GREEN (1112 -276);
FORCEPROP 2 LAST CDS_XR_PAGE_TITLE CR-117 : @S9S_MB_2U_LIB.S9S_MB_2U(SCH_1):PAGE117
J 0
(-3015 4925);
DISPLAY 0.638298 (-3015 4925);
PAINT PINK (-3015 4925);
DISPLAY INVISIBLE (-3015 4925);
FORCEPROP 1 LAST COMMENT_BODY TRUE
J 0
(4887 -338);
DISPLAY 0.978723 (4887 -338);
PAINT GREEN (4887 -338);
DISPLAY INVISIBLE (4887 -338);
FORCEPROP 2 LAST PAGE_BORDER TRUE
J 0
(-3015 4925);
DISPLAY 0.638298 (-3015 4925);
PAINT PINK (-3015 4925);
DISPLAY INVISIBLE (-3015 4925);
FORCEPROP 1 LAST CDS_LMAN_SYM_OUTLINE -9475,6775,100,-125
J 0
(4875 -325);
DISPLAY 0.468085 (4875 -325);
PAINT GREEN (4875 -325);
DISPLAY INVISIBLE (4875 -325);
FORCEPROP 2 LAST CDS_LIB pure_quanta
J 0
(4875 -325);
PAINT MONO (4875 -325);
DISPLAY INVISIBLE (4875 -325);
WIRE 16 -1 (-1875 3750)(-1875 3875);
WIRE 16 -1 (-1075 3750)(-1075 3875);
WIRE 16 -1 (-3100 4900)(-3100 5000);
WIRE 16 -1 (-2825 4900)(-2825 5000);
WIRE 16 -1 (-2825 5200)(-2825 5325);
WIRE 16 -1 (-2825 5325)(-1400 5325);
FORCEPROP 0 LAST CDS_PHYS_NET_NAME H_PMAX_TRIGGER_IO_CPU1
J 0
(-2762 5366);
PAINT MONO (-2762 5366);
DISPLAY INVISIBLE (-2762 5366);
FORCEPROP 2 LAST SIG_NAME H_PMAX_TRIGGER_IO_CPU1
J 0
(-2687 5334);
DISPLAY 0.680851 (-2687 5334);
PAINT WHITE (-2687 5334);
WIRE 16 -1 (-1400 5425)(-3100 5425);
FORCEPROP 0 LAST CDS_PHYS_NET_NAME H_PMAX_TRIGGER_IO_CPU1
J 0
(-2762 5466);
PAINT MONO (-2762 5466);
DISPLAY INVISIBLE (-2762 5466);
FORCEPROP 2 LAST SIG_NAME H_PMAX_TRIGGER_IO_CPU0
J 0
(-2687 5434);
DISPLAY 0.680851 (-2687 5434);
PAINT WHITE (-2687 5434);
WIRE 16 -1 (-3100 5200)(-3100 5425);
WIRE 16 -1 (-1875 3350)(-2075 3350);
FORCEPROP 0 LAST CDS_PHYS_NET_NAME H_PMAX_TRIGGER_IO_CPU1
J 0
(-2012 3391);
PAINT MONO (-2012 3391);
DISPLAY INVISIBLE (-2012 3391);
WIRE 16 -1 (-1875 3550)(-1875 3350);
WIRE 16 -1 (-1875 3350)(-1075 3350);
FORCEPROP 2 LAST SIG_NAME H_CPU_PM_FAST_WAKE_N
J 0
(-1787 3359);
DISPLAY 0.680851 (-1787 3359);
PAINT WHITE (-1787 3359);
WIRE 16 -1 (-800 3350)(-1075 3350);
WIRE 16 -1 (-1075 3550)(-1075 3350);
WIRE 16 -1 (450 3350)(-600 3350);
FORCEPROP 0 LAST CDS_PHYS_NET_NAME H_PMAX_TRIGGER_IO_CPU1
J 0
(-537 3391);
PAINT MONO (-537 3391);
DISPLAY INVISIBLE (-537 3391);
FORCEPROP 2 LAST SIG_NAME H_CPU1_PM_FAST_WAKE_N
J 0
(-362 3359);
DISPLAY 0.680851 (-362 3359);
PAINT WHITE (-362 3359);
WIRE 16 -1 (-2275 3350)(-3350 3350);
FORCEPROP 0 LAST CDS_PHYS_NET_NAME H_PMAX_TRIGGER_IO_CPU1
J 0
(-3287 3391);
PAINT MONO (-3287 3391);
DISPLAY INVISIBLE (-3287 3391);
FORCEPROP 2 LAST SIG_NAME H_CPU0_PM_FAST_WAKE_N
J 0
(-3212 3359);
DISPLAY 0.680851 (-3212 3359);
PAINT WHITE (-3212 3359);
DOT 1 (-1875 3350);
DOT 1 (-1075 3350);
QUIT
